FILE_TYPE = CONNECTIVITY;
{Allegro Design Entry HDL 17.2-2016 S081 (4005846) 1/11/2022}
"PAGE_NUMBER" = 317;
0"NC";
1"GND\g";
2"GND\g";
3"PRSNT_CABLE_SWB_B2_N";
4"NC_J107_A1";
5"P5E_CPU0_PE0_RX_DN<7>";
6"P5E_CPU0_PE0_RX_DP<7>";
7"P5E_CPU0_PE4_RX_DN<8>";
8"P5E_CPU0_PE4_RX_DP<8>";
9"P5E_CPU0_PE4_TX_C_DP<9>";
10"P5E_CPU0_PE4_TX_C_DN<9>";
11"P5E_CPU0_PE0_RX_DP<1>";
12"SWB_HSC_PWRGD";
13"SWB_HSC_EN_BUF";
14"P5E_CPU0_PE0_RX_DN<1>";
15"P5E_CPU0_PE4_RX_DN<14>";
16"P5E_CPU0_PE4_RX_DP<14>";
17"P5E_CPU0_PE0_TX_C_DN<1>";
18"P5E_CPU0_PE0_TX_C_DP<1>";
19"P5E_CPU0_PE4_RX_DN<13>";
20"P5E_CPU0_PE0_RX_DN<3>";
21"NC_J107_A5";
22"NC_J107_N6";
23"P5E_CPU0_PE0_RX_DN<2>";
24"P5E_CPU0_PE4_TX_C_DN<14>";
25"P5E_CPU0_PE0_TX_C_DN<0>";
26"P5E_CPU0_PE4_RX_DN<15>";
27"P5E_CPU0_PE0_RX_DP<0>";
28"P5E_CPU0_PE0_RX_DN<0>";
29"P5E_CPU0_PE4_TX_C_DP<15>";
30"P5E_CPU0_PE0_TX_C_DP<0>";
31"P5E_CPU0_PE4_TX_C_DN<15>";
32"P5E_CPU0_PE4_RX_DP<15>";
33"NC_J107_A3";
34"P5E_CPU0_PE0_RX_DP<5>";
35"P5E_CPU0_PE4_RX_DN<10>";
36"P5E_CPU0_PE4_RX_DP<10>";
37"P5E_CPU0_PE0_TX_C_DP<5>";
38"P5E_CPU0_PE4_TX_C_DP<10>";
39"P5E_CPU0_PE0_RX_DN<6>";
40"P5E_CPU0_PE0_RX_DP<6>";
41"P5E_CPU0_PE0_TX_C_DP<6>";
42"P5E_CPU0_PE0_TX_C_DN<7>";
43"P5E_CPU0_PE0_TX_C_DP<7>";
44"P5E_CPU0_PE0_TX_C_DN<6>";
45"P5E_CPU0_PE4_RX_DP<9>";
46"P5E_CPU0_PE4_RX_DN<9>";
47"P5E_CPU0_PE0_TX_C_DN<5>";
48"P5E_CPU0_PE4_TX_C_DN<12>";
49"P5E_CPU0_PE4_RX_DP<12>";
50"P5E_CPU0_PE0_TX_C_DP<3>";
51"NC_J107_N4";
52"P5E_CPU0_PE4_TX_C_DP<14>";
53"P5E_CPU0_PE0_TX_C_DP<4>";
54"P5E_CPU0_PE4_TX_C_DN<11>";
55"P5E_CPU0_PE4_TX_C_DP<8>";
56"P5E_CPU0_PE0_RX_DN<4>";
57"P5E_CPU0_PE0_RX_DP<4>";
58"P5E_CPU0_PE4_RX_DP<11>";
59"P5E_CPU0_PE4_RX_DN<11>";
60"P5E_CPU0_PE0_TX_C_DN<4>";
61"P5E_CPU0_PE4_TX_C_DP<11>";
62"P5E_CPU0_PE0_RX_DN<5>";
63"P5E_CPU0_PE4_TX_C_DN<10>";
64"P5E_CPU0_PE4_TX_C_DN<8>";
65"P5E_CPU0_PE0_RX_DP<2>";
66"P5E_CPU0_PE4_TX_C_DN<13>";
67"P5E_CPU0_PE4_TX_C_DP<13>";
68"P5E_CPU0_PE0_TX_C_DN<3>";
69"P5E_CPU0_PE4_RX_DN<12>";
70"P5E_CPU0_PE0_RX_DP<3>";
71"P5E_CPU0_PE0_TX_C_DP<2>";
72"P5E_CPU0_PE0_TX_C_DN<2>";
73"P5E_CPU0_PE4_RX_DP<13>";
74"P5E_CPU0_PE4_TX_C_DP<12>";
%"UNIVERSAL_GND"
"1","(-2275,-1475)","0","logical_power","I19";
;
CDS_LIB"logical_power"
HDL_POWER"GND";
"A"1;
%"CONN112_10137002101LF"
"1","(-1175,425)","0","pure_quanta","I38";
;
PART_NUMBER"DFHSB2FR012"
MATERIAL"IO"
PART_TYPE"THLF"
LOCATION"J107"
CDS_LIB"pure_quanta"
CDS_LMAN_SYM_OUTLINE"-775,1650,775,-1650"
NEEDS_NO_SIZE"TRUE"
VALUE"CONN112_10137002-101LF"
$SEC"1"
CDS_SEC"1";
"N8"
$PN"N8"13;
"M8"
$PN"M8"1;
"N7"
$PN"N7"1;
"M7"
$PN"M7"52;
"N6"
$PN"N6"22;
"M6"
$PN"M6"1;
"N5"
$PN"N5"1;
"M5"
$PN"M5"74;
"L5"
$PN"L5"48;
"L6"
$PN"L6"67;
"L7"
$PN"L7"24;
"L8"
$PN"L8"29;
"K5"
$PN"K5"1;
"K6"
$PN"K6"66;
"K7"
$PN"K7"1;
"K8"
$PN"K8"31;
"J5"
$PN"J5"50;
"J6"
$PN"J6"1;
"J7"
$PN"J7"18;
"J8"
$PN"J8"1;
"I5"
$PN"I5"68;
"I6"
$PN"I6"71;
"I7"
$PN"I7"17;
"I8"
$PN"I8"30;
"H5"
$PN"H5"1;
"H6"
$PN"H6"72;
"H7"
$PN"H7"1;
"H8"
$PN"H8"25;
"G5"
$PN"G5"49;
"G6"
$PN"G6"1;
"G7"
$PN"G7"16;
"G8"
$PN"G8"1;
"F5"
$PN"F5"69;
"F6"
$PN"F6"19;
"F7"
$PN"F7"15;
"F8"
$PN"F8"26;
"E5"
$PN"E5"1;
"E6"
$PN"E6"73;
"E7"
$PN"E7"1;
"E8"
$PN"E8"32;
"D5"
$PN"D5"20;
"D6"
$PN"D6"1;
"D7"
$PN"D7"14;
"D8"
$PN"D8"1;
"C5"
$PN"C5"70;
"C6"
$PN"C6"65;
"C7"
$PN"C7"11;
"C8"
$PN"C8"27;
"B5"
$PN"B5"1;
"B6"
$PN"B6"23;
"B7"
$PN"B7"1;
"B8"
$PN"B8"28;
"A5"
$PN"A5"21;
"A6"
$PN"A6"1;
"A7"
$PN"A7"12;
"A8"
$PN"A8"1;
%"UNIVERSAL_GND"
"1","(2175,-1525)","0","logical_power","I57";
;
CDS_LIB"logical_power"
HDL_POWER"GND";
"A"2;
%"CONN112_10137002101LF"
"2","(3325,425)","0","pure_quanta","I58";
;
PART_NUMBER"DFHSB2FR012"
PART_TYPE"THLF"
MATERIAL"IO"
LOCATION"J107"
CDS_LIB"pure_quanta"
CDS_LMAN_SYM_OUTLINE"-775,1650,775,-1650"
VALUE"CONN112_10137002-101LF"
NEEDS_NO_SIZE"TRUE"
$SEC"2"
CDS_SEC"2";
"N4"
$PN"N4"51;
"M4"
$PN"M4"2;
"N3"
$PN"N3"2;
"M3"
$PN"M3"38;
"N2"
$PN"N2"3;
"M2"
$PN"M2"2;
"N1"
$PN"N1"2;
"M1"
$PN"M1"55;
"L1"
$PN"L1"64;
"L2"
$PN"L2"9;
"L3"
$PN"L3"63;
"L4"
$PN"L4"54;
"K1"
$PN"K1"2;
"K2"
$PN"K2"10;
"K3"
$PN"K3"2;
"K4"
$PN"K4"61;
"J1"
$PN"J1"43;
"J2"
$PN"J2"2;
"J3"
$PN"J3"37;
"J4"
$PN"J4"2;
"I1"
$PN"I1"42;
"I2"
$PN"I2"41;
"I3"
$PN"I3"47;
"I4"
$PN"I4"53;
"H1"
$PN"H1"2;
"H2"
$PN"H2"44;
"H3"
$PN"H3"2;
"H4"
$PN"H4"60;
"G1"
$PN"G1"8;
"G2"
$PN"G2"2;
"G3"
$PN"G3"36;
"G4"
$PN"G4"2;
"F1"
$PN"F1"7;
"F2"
$PN"F2"46;
"F3"
$PN"F3"35;
"F4"
$PN"F4"59;
"E1"
$PN"E1"2;
"E2"
$PN"E2"45;
"E3"
$PN"E3"2;
"E4"
$PN"E4"58;
"D1"
$PN"D1"6;
"D2"
$PN"D2"2;
"D3"
$PN"D3"34;
"D4"
$PN"D4"2;
"C1"
$PN"C1"5;
"C2"
$PN"C2"40;
"C3"
$PN"C3"62;
"C4"
$PN"C4"57;
"B1"
$PN"B1"2;
"B2"
$PN"B2"39;
"B3"
$PN"B3"2;
"B4"
$PN"B4"56;
"A1"
$PN"A1"4;
"A2"
$PN"A2"2;
"A3"
$PN"A3"33;
"A4"
$PN"A4"2;
END.
